FILE_TYPE = MULTI_PHYS_TABLE;

PART 'Q_INDUCTOR4P_14'

{========================================================================================}
:VALUE                 | PART_TYPE | MATERIAL | PART_NUMBER    = STANDARD        | LIFECYCLE      | PART_NUMBER   | JEDEC_TYPE                    | CURRENT | DESCRIPTION                                | MANUFTR | MANUF_PN               | RD_CMPLS_LVL | CMPLS_LVL | CLASS      | DIP_SMD | FROM_PJ       | DATA                           | FP_ECN            | EE_CHECK_LIST     | STATUS | PREFERENCE | NOT_INSERT | DAY        ;
{========================================================================================}
 'SMB-665025'          | 'SMLF'    | 'IND'    | 'CX665025001'(!) = ''              | ''             | 'CX665025001' |'L_SMB665025'| '10A'   | 'EMI FILTER SMB-665025(33OHM,10A)'         | 'MAG'   | 'SMB-665025'           | ''           | 'EP'      | 'DISCRETE' | ''      | 'A05-DEMON'   | 'MAG_SMB-665025.pdf'           | 'L_SMB665025.DOC' | 'L_SMB665025.xls' | ''     | ''         | ''         | '20110222'
 'SMB-665025'          | 'SMLF'    | 'EMPTY'  | 'CX665025001'(!) = ''              | ''             | 'CX665025001' |'L_SMB665025'| '10A'   | 'EMI FILTER SMB-665025(33OHM,10A)'         | 'MAG'   | 'SMB-665025'           | ''           | 'EP'      | 'DISCRETE' | ''      | 'A05-DEMON'   | 'MAG_SMB-665025.pdf'           | 'L_SMB665025.DOC' | 'L_SMB665025.xls' | ''     | ''         | ''         | '20110222'
 'ACM2012-201-2P-T'    | 'SMLF'    | 'IND'    | 'CXCM2012001'(!) = ''              | ''             | 'CXCM2012001' |'L_ACM2012'| '350MA' | 'EMI FILTER ACM2012-201-2P-T(50V,350MA)'   | 'TDK'   | 'ACM2012-201-2P-T'     | ''           | 'EP_Tmp'  | 'DISCRETE' | ''      | 'A06-EDISON'  | 'TDK_ACM-SERIES.pdf'           | ''                | 'L_ACM2012.xls'   | ''     | ''         | ''         | '20110222'
 'ACM2012-201-2P-T'    | 'SMLF'    | 'EMPTY'  | 'CXCM2012001'(!) = ''              | ''             | 'CXCM2012001' |'L_ACM2012'| '350MA' | 'EMI FILTER ACM2012-201-2P-T(50V,350MA)'   | 'TDK'   | 'ACM2012-201-2P-T'     | ''           | 'EP_Tmp'  | 'DISCRETE' | ''      | 'A06-EDISON'  | 'TDK_ACM-SERIES.pdf'           | ''                | 'L_ACM2012.xls'   | ''     | ''         | ''         | '20110222'
 'ACM2012H-900-2P-T00' | 'SMLF'    | 'IND'    | 'CX12H900001'(!) = 'End of Design' | 'End of Life'  | 'CX12H900001' |'L_ACM2012_EOL'| '300MA' | 'EMI FILT ACM2012H-900-2P-T00(20V300MA)'   | 'TDK'   | 'ACM2012H-900-2P-T00'  | ''           | 'EP'      | 'DISCRETE' | ''      | 'S99C-MINGLI' | 'ACM2012H-900-2P-x00.pdf'      | ''                | ''                | ''     | ''         | ''         | '20110222'
 'ACM2012H-900-2P-T00' | 'SMLF'    | 'EMPTY'  | 'CX12H900001'(!) = 'End of Design' | 'End of Life'  | 'CX12H900001' |'L_ACM2012_EOL'| '300MA' | 'EMI FILT ACM2012H-900-2P-T00(20V300MA)'   | 'TDK'   | 'ACM2012H-900-2P-T00'  | ''           | 'EP'      | 'DISCRETE' | ''      | 'S99C-MINGLI' | 'ACM2012H-900-2P-x00.pdf'      | ''                | ''                | ''     | ''         | ''         | '20110222'
 '20V/200MA'           | 'SMLF'    | 'IND'    | 'CXCM2012002'(!) = 'End of Design' | 'Comp-Approve' | 'CXCM2012002' |'L_ACM2012XA'| '200MA' | 'EMI FILTER ACM2012-900-2P-T(20V,200MA)EP' | 'TDK'   | 'ACM2012-900-2P-T'     | 'EP'         | 'EP'      | 'DISCRETE' | ''      | 'JB9-JACK'    | 'ACM2012E-series_rev2011.pdf'  | ''                | ''                | ''     | ''         | ''         | '20120525'
 '20V/200MA'           | 'SMLF'    | 'EMPTY'  | 'CXCM2012002'(!) = 'End of Design' | 'Comp-Approve' | 'CXCM2012002' |'L_ACM2012XA'| '200MA' | 'EMI FILTER ACM2012-900-2P-T(20V,200MA)EP' | 'TDK'   | 'ACM2012-900-2P-T'     | 'EP'         | 'EP'      | 'DISCRETE' | ''      | 'JB9-JACK'    | 'ACM2012E-series_rev2011.pdf'  | ''                | ''                | ''     | ''         | ''         | '20120525'
 '90/400MA'            | 'SMLF'    | 'IND'    | 'CX02012E000'(!) = 'End of Design' | 'End of Life'  | 'CX02012E000' |'L_ACM2012XA_EOL'| '400MA' | 'EMI FILTER ACM2012E-900-2P-T-00 90,4OOMA' | 'TDK'   | 'ACM2012E-900-2P-T-00' | 'EP(V1)'     | ''        | 'DISCRETE' | ''      | 'JB9-JACK'    | 'ACM2012E-series_rev2011.pdf'  | ''                | ''                | ''     | ''         | ''         | '20120525'
 '90/400MA'            | 'SMLF'    | 'EMPTY'  | 'CX02012E000'(!) = 'End of Design' | 'End of Life'  | 'CX02012E000' |'L_ACM2012XA_EOL'| '400MA' | 'EMI FILTER ACM2012E-900-2P-T-00 90,4OOMA' | 'TDK'   | 'ACM2012E-900-2P-T-00' | 'EP(V1)'     | ''        | 'DISCRETE' | ''      | 'JB9-JACK'    | 'ACM2012E-series_rev2011.pdf'  | ''                | ''                | ''     | ''         | ''         | '20120525'
 '150NH'               | 'SMLF'    | 'IND'    | 'CV+15^0TZ00'(!) = ''              | ''             | 'CV+15^0TZ00' |'L_VLBC12060120R10LF3_12X6XA'| '82A'   | 'IND SMD 150NH 15% 82A(VLBC12060120R15LF3' | 'TDK'   | 'VLBC12060120R15LF3'   | 'EP(V1)'     | ''        | 'DISCRETE' | ''      | 'S8Z-FRANK'   | 'TDK_VLBC12060120R15LF3.pdf'   | ''                | ''                | ''     | ''         | ''         | '20200527'
 '150NH'               | 'SMLF'    | 'EMPTY'  | 'CV+15^0TZ00'(!) = ''              | ''             | 'CV+15^0TZ00' |'L_VLBC12060120R10LF3_12X6XA'| '82A'   | 'IND SMD 150NH 15% 82A(VLBC12060120R15LF3' | 'TDK'   | 'VLBC12060120R15LF3'   | 'EP(V1)'     | ''        | 'DISCRETE' | ''      | 'S8Z-FRANK'   | 'TDK_VLBC12060120R15LF3.pdf'   | ''                | ''                | ''     | ''         | ''         | '20200527'
 '105NH'               | 'SMLF'    | 'IND'    | 'CV+10^0TZ02'(!) = ''              | ''             | 'CV+10^0TZ02' |'L_VLBC12060120R10LF3_12X6XA'| '125A'  | 'IND SMD 105NH+-15%125A(VLBC12060120R10LF' | 'TDK'   | 'VLBC12060120R10LF3'   | 'EP(V1)'     | ''        | 'DISCRETE' | ''      | 'S8Z-FRANK'   | 'TDK_VLBC12060120R10LF3.pdf'   | ''                | ''                | ''     | ''         | ''         | '20200527'
 '105NH'               | 'SMLF'    | 'EMPTY'  | 'CV+10^0TZ02'(!) = ''              | ''             | 'CV+10^0TZ02' |'L_VLBC12060120R10LF3_12X6XA'| '125A'  | 'IND SMD 105NH+-15%125A(VLBC12060120R10LF' | 'TDK'   | 'VLBC12060120R10LF3'   | 'EP(V1)'     | ''        | 'DISCRETE' | ''      | 'S8Z-FRANK'   | 'TDK_VLBC12060120R10LF3.pdf'   | ''                | ''                | ''     | ''         | ''         | '20200527'
 '170NH'               | 'SMLF'    | 'IND'    | 'CV+17^0EZ02'(!) = ''              | ''             | 'CV+17^0EZ02' |'L_VLBC12060120R10LF3_12X6XA'| '70A'   | 'IND SMD 170NH 15% 70A(VLBC12060120R17LF3' | 'TDK'   | 'VLBC12060120R17LF3'   | 'EP(V1)'     | ''        | 'DISCRETE' | ''      | 'S8Z-FRANK'   | 'TDK_VLBC12060120R17LF3.pdf'   | ''                | ''                | ''     | ''         | ''         | '20200527'
 '170NH'               | 'SMLF'    | 'EMPTY'  | 'CV+17^0EZ02'(!) = ''              | ''             | 'CV+17^0EZ02' |'L_VLBC12060120R10LF3_12X6XA'| '70A'   | 'IND SMD 170NH 15% 70A(VLBC12060120R17LF3' | 'TDK'   | 'VLBC12060120R17LF3'   | 'EP(V1)'     | ''        | 'DISCRETE' | ''      | 'S8Z-FRANK'   | 'TDK_VLBC12060120R17LF3.pdf'   | ''                | ''                | ''     | ''         | ''         | '20200527'
 '105NH'               | 'SMLF'    | 'IND'    | 'CV+11^0EZ00'(!) = ''              | ''             | 'CV+11^0EZ00' |'L_TLM1211Q-111QL_12X6'| '118A'  | 'IND SMD 105NH 15% 118A(TLM1211Q-111QL)'   | 'DTA'   | 'TLM1211Q-111QL'       | 'EP(V1)'     | ''        | 'DISCRETE' | ''      | 'S8Z-FRANK'   | 'DTA_TLM1211Q-111QL.pdf'       | ''                | ''                | ''     | ''         | ''         | '20200528'
 '105NH'               | 'SMLF'    | 'EMPTY'  | 'CV+11^0EZ00'(!) = ''              | ''             | 'CV+11^0EZ00' |'L_TLM1211Q-111QL_12X6'| '118A'  | 'IND SMD 105NH 15% 118A(TLM1211Q-111QL)'   | 'DTA'   | 'TLM1211Q-111QL'       | 'EP(V1)'     | ''        | 'DISCRETE' | ''      | 'S8Z-FRANK'   | 'DTA_TLM1211Q-111QL.pdf'       | ''                | ''                | ''     | ''         | ''         | '20200528'
 '150NH'               | 'SMLF'    | 'IND'    | 'CV+15^0EZ05'(!) = ''              | ''             | 'CV+15^0EZ05' |'L_TLM1211Q-111QL_12X6'| '84A'   | 'IND SMD 150NH 15% 84A(TLM1211Q-151QL)'    | 'DTA'   | 'TLM1211Q-151QL'       | 'EP(V1)'     | ''        | 'DISCRETE' | ''      | 'S8Z-FRANK'   | 'DTA_TLM1211Q-151QL.pdf'       | ''                | ''                | ''     | ''         | ''         | '20200528'
 '150NH'               | 'SMLF'    | 'EMPTY'  | 'CV+15^0EZ05'(!) = ''              | ''             | 'CV+15^0EZ05' |'L_TLM1211Q-111QL_12X6'| '84A'   | 'IND SMD 150NH 15% 84A(TLM1211Q-151QL)'    | 'DTA'   | 'TLM1211Q-151QL'       | 'EP(V1)'     | ''        | 'DISCRETE' | ''      | 'S8Z-FRANK'   | 'DTA_TLM1211Q-151QL.pdf'       | ''                | ''                | ''     | ''         | ''         | '20200528'
 '170NH'               | 'SMLF'    | 'IND'    | 'CV+17^0EZ03'(!) = ''              | ''             | 'CV+17^0EZ03' |'L_TLM1211Q-111QL_12X6'| '70A'   | 'IND SMD 170NH 15% 70A(TLM1211Q-171QL)'    | 'DTA'   | 'TLM1211Q-171QL'       | 'EP(V1)'     | ''        | 'DISCRETE' | ''      | 'S8Z-FRANK'   | 'DTA_TLM1211Q-171QL.pdf'       | ''                | ''                | ''     | ''         | ''         | '20200602'
 '170NH'               | 'SMLF'    | 'EMPTY'  | 'CV+17^0EZ03'(!) = ''              | ''             | 'CV+17^0EZ03' |'L_TLM1211Q-111QL_12X6'| '70A'   | 'IND SMD 170NH 15% 70A(TLM1211Q-171QL)'    | 'DTA'   | 'TLM1211Q-171QL'       | 'EP(V1)'     | ''        | 'DISCRETE' | ''      | 'S8Z-FRANK'   | 'DTA_TLM1211Q-171QL.pdf'       | ''                | ''                | ''     | ''         | ''         | '20200602'
 '105NH'               | 'SMLF'    | 'IND'    | 'CV+10^0EZ01'(!) = ''              | ''             | 'CV+10^0EZ01' |'L_VLBC12060120R10LF3_12X6XA'| '125A'  | 'IND SMD 105NH 15% 125A(VLBUC12060120R10)' | 'TDK'   | 'VLBUC12060120R10LF3'  | 'EP(V1)'     | ''        | 'DISCRETE' | ''      | 'S8Z-FRANK'   | 'TDK_VLBUC12060120R10LF3.pdf'  | ''                | ''                | ''     | ''         | ''         | '20200617'
 '105NH'               | 'SMLF'    | 'EMPTY'  | 'CV+10^0EZ01'(!) = ''              | ''             | 'CV+10^0EZ01' |'L_VLBC12060120R10LF3_12X6XA'| '125A'  | 'IND SMD 105NH 15% 125A(VLBUC12060120R10)' | 'TDK'   | 'VLBUC12060120R10LF3'  | 'EP(V1)'     | ''        | 'DISCRETE' | ''      | 'S8Z-FRANK'   | 'TDK_VLBUC12060120R10LF3.pdf'  | ''                | ''                | ''     | ''         | ''         | '20200617'
 '170NH'               | 'SMLF'    | 'IND'    | 'CV+17^0EZ04'(!) = ''              | ''             | 'CV+17^0EZ04' |'L_VLBC12060120R10LF3_12X6XA'| '70A'   | 'IND SMD 170NH 15% 70A(VLBUC12060120R17)'  | 'TDK'   | 'VLBUC12060120R17LF3'  | 'EP(V1)'     | ''        | 'DISCRETE' | ''      | 'S8Z-FRANK'   | 'TDK_VLBUC12060120R17LF3.pdf'  | ''                | ''                | ''     | ''         | ''         | '20200617'
 '170NH'               | 'SMLF'    | 'EMPTY'  | 'CV+17^0EZ04'(!) = ''              | ''             | 'CV+17^0EZ04' |'L_VLBC12060120R10LF3_12X6XA'| '70A'   | 'IND SMD 170NH 15% 70A(VLBUC12060120R17)'  | 'TDK'   | 'VLBUC12060120R17LF3'  | 'EP(V1)'     | ''        | 'DISCRETE' | ''      | 'S8Z-FRANK'   | 'TDK_VLBUC12060120R17LF3.pdf'  | ''                | ''                | ''     | ''         | ''         | '20200617'
 '150NH'               | 'SMLF'    | 'IND'    | 'CV+15^0EZ06'(!) = ''              | ''             | 'CV+15^0EZ06' |'L_VLBC12060120R10LF3_12X6XA'| '82A'   | 'IND SMD 150NH 15% 82A(VLBUC12060120R15)'  | 'TDK'   | 'VLBUC12060120R15LF3'  | 'EP(V1)'     | ''        | 'DISCRETE' | ''      | 'S8Z-FRANK'   | 'TDK_VLBUC12060120R15LF3.pdf'  | ''                | ''                | ''     | ''         | ''         | '20200617'
 '150NH'               | 'SMLF'    | 'EMPTY'  | 'CV+15^0EZ06'(!) = ''              | ''             | 'CV+15^0EZ06' |'L_VLBC12060120R10LF3_12X6XA'| '82A'   | 'IND SMD 150NH 15% 82A(VLBUC12060120R15)'  | 'TDK'   | 'VLBUC12060120R15LF3'  | 'EP(V1)'     | ''        | 'DISCRETE' | ''      | 'S8Z-FRANK'   | 'TDK_VLBUC12060120R15LF3.pdf'  | ''                | ''                | ''     | ''         | ''         | '20200617'
 '150NH'               | 'SMLF'    | 'IND'    | 'CV+15^0EZ09'(!) = ''              | ''             | 'CV+15^0EZ09' |'L_TLM117513Q-151QL_11X7-5XA'| '82A'   | 'IND SMD 150NH 15% 82A(TLM117513Q-151QL)'  | 'DTA'   | 'TLM117513Q-151QL'     | 'EP(V1)'     | ''        | 'DISCRETE' | ''      | 'S6Q-KIMI'    | 'DTA_TLM117513Q-151QL.pdf'     | ''                | ''                | ''     | ''         | ''         | '20200825'
 '150NH'               | 'SMLF'    | 'EMPTY'  | 'CV+15^0EZ09'(!) = ''              | ''             | 'CV+15^0EZ09' |'L_TLM117513Q-151QL_11X7-5XA'| '82A'   | 'IND SMD 150NH 15% 82A(TLM117513Q-151QL)'  | 'DTA'   | 'TLM117513Q-151QL'     | 'EP(V1)'     | ''        | 'DISCRETE' | ''      | 'S6Q-KIMI'    | 'DTA_TLM117513Q-151QL.pdf'     | ''                | ''                | ''     | ''         | ''         | '20200825'
 '150NH'               | 'SMLF'    | 'IND'    | 'CV+15^0TZ01'(!) = ''              | ''             | 'CV+15^0TZ01' |'L_TLM117513Q-151QL_11X7-5XA'| '82A'   | 'IND SMD 150NH 15% 82A(TLM117513Q-151AQL)' | 'DTA'   | 'TLM117513Q-151AQL'    | 'EP(V1)'     | ''        | 'DISCRETE' | ''      | 'S6Q-KIMI'    | 'DTA_TLM117513Q-151AQL.pdf'    | ''                | ''                | ''     | ''         | ''         | '20200827'
 '150NH'               | 'SMLF'    | 'EMPTY'  | 'CV+15^0TZ01'(!) = ''              | ''             | 'CV+15^0TZ01' |'L_TLM117513Q-151QL_11X7-5XA'| '82A'   | 'IND SMD 150NH 15% 82A(TLM117513Q-151AQL)' | 'DTA'   | 'TLM117513Q-151AQL'    | 'EP(V1)'     | ''        | 'DISCRETE' | ''      | 'S6Q-KIMI'    | 'DTA_TLM117513Q-151AQL.pdf'    | ''                | ''                | ''     | ''         | ''         | '20200827'
 '150NH'               | 'SMLF'    | 'IND'    | 'CV+15^0EZ10'(!) = ''              | ''             | 'CV+15^0EZ10' |'L_VLBC12060120R10LF3_12X6XA'| '82A'   | 'IND SMD 150NH 15% 82A(PGL6181.151HLT)'    | 'PLE'   | 'PGL6181.151HLT'       | 'EP(V1)'     | ''        | 'DISCRETE' | ''      | 'S8Z-BRIAN'   | 'PLE_PGL6181.151HLT.pdf'       | ''                | ''                | ''     | ''         | ''         | '20201012'
 '150NH'               | 'SMLF'    | 'EMPTY'  | 'CV+15^0EZ10'(!) = ''              | ''             | 'CV+15^0EZ10' |'L_VLBC12060120R10LF3_12X6XA'| '82A'   | 'IND SMD 150NH 15% 82A(PGL6181.151HLT)'    | 'PLE'   | 'PGL6181.151HLT'       | 'EP(V1)'     | ''        | 'DISCRETE' | ''      | 'S8Z-BRIAN'   | 'PLE_PGL6181.151HLT.pdf'       | ''                | ''                | ''     | ''         | ''         | '20201012'
 '150NH'               | 'SMLF'    | 'IND'    | 'CV+15^0TZ04'(!) = 'End of Design' | 'Comp-Approve' | 'CV+15^0TZ04' |'L_TLM117513Q-151QL_11X7-5XA'| '82A'   | 'IND SMD 150NH 15% 82A(PGL6303.151HLT)'    | 'PLE'   | 'PGL6303.151HLT'       | 'EP(V1)'     | ''        | 'DISCRETE' | ''      | 'S6X-KIMI'    | 'PLE_PGL6303.151HLT.pdf'       | ''                | ''                | ''     | ''         | ''         | '20201026'
 '150NH'               | 'SMLF'    | 'EMPTY'  | 'CV+15^0TZ04'(!) = 'End of Design' | 'Comp-Approve' | 'CV+15^0TZ04' |'L_TLM117513Q-151QL_11X7-5XA'| '82A'   | 'IND SMD 150NH 15% 82A(PGL6303.151HLT)'    | 'PLE'   | 'PGL6303.151HLT'       | 'EP(V1)'     | ''        | 'DISCRETE' | ''      | 'S6X-KIMI'    | 'PLE_PGL6303.151HLT.pdf'       | ''                | ''                | ''     | ''         | ''         | '20201026'
 '150NH'               | 'SMLF'    | 'IND'    | 'CV+15^0EZ11'(!) = ''              | ''             | 'CV+15^0EZ11' |'L_VLBC12060120R10LF3_12X6XA'| '84A'   | 'IND SMD 150NH 15% 84A(TLM1212Q-151QL)'    | 'DTA'   | 'TLM1212Q-151QL'       | 'EP(V1)'     | ''        | 'DISCRETE' | ''      | 'S8Z-BRIAN'   | 'DTA_TLM1212Q-151QL.pdf'       | ''                | ''                | ''     | ''         | ''         | '20201109'
 '150NH'               | 'SMLF'    | 'EMPTY'  | 'CV+15^0EZ11'(!) = ''              | ''             | 'CV+15^0EZ11' |'L_VLBC12060120R10LF3_12X6XA'| '84A'   | 'IND SMD 150NH 15% 84A(TLM1212Q-151QL)'    | 'DTA'   | 'TLM1212Q-151QL'       | 'EP(V1)'     | ''        | 'DISCRETE' | ''      | 'S8Z-BRIAN'   | 'DTA_TLM1212Q-151QL.pdf'       | ''                | ''                | ''     | ''         | ''         | '20201109'
 '150NH'               | 'SMLF'    | 'IND'    | 'CV+15^0EZ07'(!) = ''              | ''             | 'CV+15^0EZ07' |'L_VLBC12060120R10LF3_12X6XA'| '82A'   | 'IND SMD 150NH 15% 82A(VLBUC12060120R15LF' | 'TDK'   | 'VLBUC12060120R15LF3N' | 'EP(V1)'     | ''        | 'DISCRETE' | ''      | 'S8Z-BRIAN'   | 'TDK_VLBUC12060120R15LF3N.pdf' | ''                | ''                | ''     | ''         | ''         | '20210302'
 '150NH'               | 'SMLF'    | 'EMPTY'  | 'CV+15^0EZ07'(!) = ''              | ''             | 'CV+15^0EZ07' |'L_VLBC12060120R10LF3_12X6XA'| '82A'   | 'IND SMD 150NH 15% 82A(VLBUC12060120R15LF' | 'TDK'   | 'VLBUC12060120R15LF3N' | 'EP(V1)'     | ''        | 'DISCRETE' | ''      | 'S8Z-BRIAN'   | 'TDK_VLBUC12060120R15LF3N.pdf' | ''                | ''                | ''     | ''         | ''         | '20210302'
 '130NH'               | 'SMLF'    | 'IND'    | 'CV+13^0EZ01'(!) = ''              | ''             | 'CV+13^0EZ01' |'L_TLM117513Q-151QL_11X7-5XA'| '98A'   | 'IND SMD 130NH 15% 98A(PGL6303.131HLT)'    | 'PLE'   | 'PGL6303.131HLT'       | 'EP(V1)'     | ''        | 'DISCRETE' | ''      | 'S6Q-KIMI'    | 'PLE_PGL6303.131HLT.pdf'       | ''                | ''                | ''     | ''         | ''         | '20210427'
 '130NH'               | 'SMLF'    | 'EMPTY'  | 'CV+13^0EZ01'(!) = ''              | ''             | 'CV+13^0EZ01' |'L_TLM117513Q-151QL_11X7-5XA'| '98A'   | 'IND SMD 130NH 15% 98A(PGL6303.131HLT)'    | 'PLE'   | 'PGL6303.131HLT'       | 'EP(V1)'     | ''        | 'DISCRETE' | ''      | 'S6Q-KIMI'    | 'PLE_PGL6303.131HLT.pdf'       | ''                | ''                | ''     | ''         | ''         | '20210427'
 '150NH'               | 'SMLF'    | 'IND'    | 'CV+15^0EZ12'(!) = ''              | ''             | 'CV+15^0EZ12' |'L_VLBC12060120R10LF3_12X6XA'| '82A'   | 'IND SMD 150NH 15% 82A(VLBUC12060120R15LF' | 'TDK'   | 'VLBUC12060120R15LF3G' | 'EP(V1)'     | ''        | 'DISCRETE' | ''      | 'S8ZE-CARLOS' | 'TDK_VLBUC12060120R15LF3G.pdf' | ''                | ''                | ''     | ''         | ''         | '20230105'
 '150NH'               | 'SMLF'    | 'EMPTY'  | 'CV+15^0EZ12'(!) = ''              | ''             | 'CV+15^0EZ12' |'L_VLBC12060120R10LF3_12X6XA'| '82A'   | 'IND SMD 150NH 15% 82A(VLBUC12060120R15LF' | 'TDK'   | 'VLBUC12060120R15LF3G' | 'EP(V1)'     | ''        | 'DISCRETE' | ''      | 'S8ZE-CARLOS' | 'TDK_VLBUC12060120R15LF3G.pdf' | ''                | ''                | ''     | ''         | ''         | '20230105'

END_PART

END.

